(kicad_sch
	(version 20250114)
	(generator "eeschema")
	(generator_version "9.0")
	(paper "A3")
	(title_block
		(title "DDR5 testbed")
		(date "2024-05-27")
		(rev "1.1.2")
		(comment 1 "www.antmicro.com")
		(comment 2 "Antmicro Ltd.")
	)
	(text "I2C peripherals"
		(exclude_from_sim no)
		(at 19.685 23.495 0)
		(effects
			(font
				(size 2.4892 2.4892)
				(thickness 0.4978)
				(bold yes)
			)
			(justify left bottom)
		)
	)
	(text "test-board:IO_U12"
		(exclude_from_sim no)
		(at 154.305 174.625 0)
		(effects
			(font
				(size 1.27 1.27)
			)
			(justify left bottom)
		)
	)
	(text "test-board:IO_U12"
		(exclude_from_sim no)
		(at 158.75 120.65 0)
		(effects
			(font
				(size 1.27 1.27)
			)
			(justify left bottom)
		)
	)
	(text "test-board:IO_V12"
		(exclude_from_sim no)
		(at 158.75 123.19 0)
		(effects
			(font
				(size 1.27 1.27)
			)
			(justify left bottom)
		)
	)
	(text "test-board:IO_V12"
		(exclude_from_sim no)
		(at 154.305 177.165 0)
		(effects
			(font
				(size 1.27 1.27)
			)
			(justify left bottom)
		)
	)
	(junction
		(at 194.31 129.54)
		(diameter 0)
		(color 0 0 0 0)
	)
	(junction
		(at 194.31 114.3)
		(diameter 0)
		(color 0 0 0 0)
	)
	(junction
		(at 189.23 68.58)
		(diameter 0)
		(color 0 0 0 0)
	)
	(junction
		(at 191.77 176.53)
		(diameter 0)
		(color 0 0 0 0)
	)
	(junction
		(at 226.695 80.01)
		(diameter 0)
		(color 0 0 0 0)
	)
	(junction
		(at 196.85 179.07)
		(diameter 0)
		(color 0 0 0 0)
	)
	(junction
		(at 189.23 80.01)
		(diameter 0)
		(color 0 0 0 0)
	)
	(junction
		(at 226.695 68.58)
		(diameter 0)
		(color 0 0 0 0)
	)
	(junction
		(at 252.095 173.99)
		(diameter 0)
		(color 0 0 0 0)
	)
	(junction
		(at 182.88 173.99)
		(diameter 0)
		(color 0 0 0 0)
	)
	(junction
		(at 182.88 162.56)
		(diameter 0)
		(color 0 0 0 0)
	)
	(no_connect
		(at 218.44 129.54)
	)
	(no_connect
		(at 195.58 127)
	)
	(no_connect
		(at 218.44 127)
	)
	(wire
		(pts
			(xy 195.58 132.08) (xy 194.31 132.08)
		)
		(stroke
			(width 0)
			(type default)
		)
	)
	(wire
		(pts
			(xy 218.44 111.76) (xy 226.06 111.76)
		)
		(stroke
			(width 0)
			(type default)
		)
	)
	(wire
		(pts
			(xy 182.88 114.3) (xy 194.31 114.3)
		)
		(stroke
			(width 0)
			(type default)
		)
	)
	(wire
		(pts
			(xy 182.88 170.815) (xy 182.88 173.99)
		)
		(stroke
			(width 0)
			(type default)
		)
	)
	(wire
		(pts
			(xy 218.44 116.84) (xy 226.06 116.84)
		)
		(stroke
			(width 0)
			(type default)
		)
	)
	(wire
		(pts
			(xy 226.695 68.58) (xy 237.49 68.58)
		)
		(stroke
			(width 0)
			(type default)
		)
	)
	(wire
		(pts
			(xy 218.44 119.38) (xy 226.06 119.38)
		)
		(stroke
			(width 0)
			(type default)
		)
	)
	(wire
		(pts
			(xy 252.73 114.3) (xy 252.73 120.65)
		)
		(stroke
			(width 0)
			(type default)
		)
	)
	(wire
		(pts
			(xy 181.61 68.58) (xy 189.23 68.58)
		)
		(stroke
			(width 0)
			(type default)
		)
	)
	(wire
		(pts
			(xy 182.88 119.38) (xy 195.58 119.38)
		)
		(stroke
			(width 0)
			(type default)
		)
	)
	(wire
		(pts
			(xy 189.23 80.01) (xy 194.31 80.01)
		)
		(stroke
			(width 0)
			(type default)
		)
	)
	(wire
		(pts
			(xy 189.23 80.01) (xy 189.23 68.58)
		)
		(stroke
			(width 0)
			(type default)
		)
	)
	(wire
		(pts
			(xy 260.35 111.76) (xy 260.35 120.65)
		)
		(stroke
			(width 0)
			(type default)
		)
	)
	(wire
		(pts
			(xy 182.88 162.56) (xy 182.88 165.735)
		)
		(stroke
			(width 0)
			(type default)
		)
	)
	(wire
		(pts
			(xy 219.71 85.09) (xy 218.44 85.09)
		)
		(stroke
			(width 0)
			(type default)
		)
	)
	(wire
		(pts
			(xy 237.49 128.27) (xy 237.49 139.7)
		)
		(stroke
			(width 0)
			(type default)
		)
	)
	(wire
		(pts
			(xy 177.8 173.99) (xy 182.88 173.99)
		)
		(stroke
			(width 0)
			(type default)
		)
	)
	(wire
		(pts
			(xy 245.11 116.84) (xy 245.11 120.65)
		)
		(stroke
			(width 0)
			(type default)
		)
	)
	(wire
		(pts
			(xy 222.25 173.99) (xy 218.44 173.99)
		)
		(stroke
			(width 0)
			(type default)
		)
	)
	(wire
		(pts
			(xy 226.695 80.01) (xy 226.695 68.58)
		)
		(stroke
			(width 0)
			(type default)
		)
	)
	(wire
		(pts
			(xy 182.88 121.92) (xy 195.58 121.92)
		)
		(stroke
			(width 0)
			(type default)
		)
	)
	(wire
		(pts
			(xy 260.35 128.27) (xy 260.35 139.7)
		)
		(stroke
			(width 0)
			(type default)
		)
	)
	(wire
		(pts
			(xy 252.73 128.27) (xy 252.73 139.7)
		)
		(stroke
			(width 0)
			(type default)
		)
	)
	(wire
		(pts
			(xy 175.26 111.76) (xy 195.58 111.76)
		)
		(stroke
			(width 0)
			(type default)
		)
	)
	(wire
		(pts
			(xy 181.61 162.56) (xy 182.88 162.56)
		)
		(stroke
			(width 0)
			(type default)
		)
	)
	(wire
		(pts
			(xy 195.58 129.54) (xy 194.31 129.54)
		)
		(stroke
			(width 0)
			(type default)
		)
	)
	(wire
		(pts
			(xy 250.825 173.99) (xy 252.095 173.99)
		)
		(stroke
			(width 0)
			(type default)
		)
	)
	(wire
		(pts
			(xy 219.71 121.92) (xy 218.44 121.92)
		)
		(stroke
			(width 0)
			(type default)
		)
	)
	(wire
		(pts
			(xy 182.88 162.56) (xy 191.77 162.56)
		)
		(stroke
			(width 0)
			(type default)
		)
	)
	(wire
		(pts
			(xy 231.14 111.76) (xy 260.35 111.76)
		)
		(stroke
			(width 0)
			(type default)
		)
	)
	(wire
		(pts
			(xy 191.77 162.56) (xy 191.77 165.735)
		)
		(stroke
			(width 0)
			(type default)
		)
	)
	(wire
		(pts
			(xy 218.44 114.3) (xy 226.06 114.3)
		)
		(stroke
			(width 0)
			(type default)
		)
	)
	(wire
		(pts
			(xy 218.44 176.53) (xy 219.71 176.53)
		)
		(stroke
			(width 0)
			(type default)
		)
	)
	(wire
		(pts
			(xy 218.44 124.46) (xy 219.71 124.46)
		)
		(stroke
			(width 0)
			(type default)
		)
	)
	(wire
		(pts
			(xy 191.77 176.53) (xy 198.12 176.53)
		)
		(stroke
			(width 0)
			(type default)
		)
	)
	(wire
		(pts
			(xy 194.945 179.07) (xy 196.85 179.07)
		)
		(stroke
			(width 0)
			(type default)
		)
	)
	(wire
		(pts
			(xy 196.85 179.07) (xy 198.12 179.07)
		)
		(stroke
			(width 0)
			(type default)
		)
	)
	(wire
		(pts
			(xy 203.2 80.01) (xy 199.39 80.01)
		)
		(stroke
			(width 0)
			(type default)
		)
	)
	(wire
		(pts
			(xy 219.71 176.53) (xy 219.71 180.34)
		)
		(stroke
			(width 0)
			(type default)
		)
	)
	(wire
		(pts
			(xy 196.85 179.07) (xy 196.85 180.34)
		)
		(stroke
			(width 0)
			(type default)
		)
	)
	(wire
		(pts
			(xy 231.14 114.3) (xy 252.73 114.3)
		)
		(stroke
			(width 0)
			(type default)
		)
	)
	(wire
		(pts
			(xy 177.8 176.53) (xy 191.77 176.53)
		)
		(stroke
			(width 0)
			(type default)
		)
	)
	(wire
		(pts
			(xy 231.14 119.38) (xy 237.49 119.38)
		)
		(stroke
			(width 0)
			(type default)
		)
	)
	(wire
		(pts
			(xy 194.31 137.16) (xy 195.58 137.16)
		)
		(stroke
			(width 0)
			(type default)
		)
	)
	(wire
		(pts
			(xy 231.14 116.84) (xy 245.11 116.84)
		)
		(stroke
			(width 0)
			(type default)
		)
	)
	(wire
		(pts
			(xy 245.11 128.27) (xy 245.11 139.7)
		)
		(stroke
			(width 0)
			(type default)
		)
	)
	(wire
		(pts
			(xy 191.77 170.815) (xy 191.77 176.53)
		)
		(stroke
			(width 0)
			(type default)
		)
	)
	(wire
		(pts
			(xy 259.715 173.99) (xy 259.715 175.26)
		)
		(stroke
			(width 0)
			(type default)
		)
	)
	(wire
		(pts
			(xy 212.725 68.58) (xy 226.695 68.58)
		)
		(stroke
			(width 0)
			(type default)
		)
	)
	(wire
		(pts
			(xy 195.58 114.3) (xy 194.31 114.3)
		)
		(stroke
			(width 0)
			(type default)
		)
	)
	(wire
		(pts
			(xy 207.645 68.58) (xy 189.23 68.58)
		)
		(stroke
			(width 0)
			(type default)
		)
	)
	(wire
		(pts
			(xy 237.49 119.38) (xy 237.49 120.65)
		)
		(stroke
			(width 0)
			(type default)
		)
	)
	(wire
		(pts
			(xy 226.695 80.01) (xy 226.695 81.28)
		)
		(stroke
			(width 0)
			(type default)
		)
	)
	(wire
		(pts
			(xy 218.44 80.01) (xy 226.695 80.01)
		)
		(stroke
			(width 0)
			(type default)
		)
	)
	(wire
		(pts
			(xy 194.31 132.08) (xy 194.31 129.54)
		)
		(stroke
			(width 0)
			(type default)
		)
	)
	(wire
		(pts
			(xy 189.23 80.01) (xy 189.23 81.28)
		)
		(stroke
			(width 0)
			(type default)
		)
	)
	(wire
		(pts
			(xy 194.31 139.7) (xy 194.31 137.16)
		)
		(stroke
			(width 0)
			(type default)
		)
	)
	(wire
		(pts
			(xy 252.095 173.99) (xy 252.095 175.26)
		)
		(stroke
			(width 0)
			(type default)
		)
	)
	(wire
		(pts
			(xy 219.71 86.36) (xy 219.71 85.09)
		)
		(stroke
			(width 0)
			(type default)
		)
	)
	(wire
		(pts
			(xy 194.31 129.54) (xy 194.31 114.3)
		)
		(stroke
			(width 0)
			(type default)
		)
	)
	(wire
		(pts
			(xy 252.095 173.99) (xy 259.715 173.99)
		)
		(stroke
			(width 0)
			(type default)
		)
	)
	(wire
		(pts
			(xy 182.88 173.99) (xy 198.12 173.99)
		)
		(stroke
			(width 0)
			(type default)
		)
	)
	(label "VDD_LED"
		(at 175.26 111.76 0)
		(effects
			(font
				(size 1.27 1.27)
			)
			(justify left bottom)
		)
	)
	(label "VDD_LED"
		(at 237.49 68.58 180)
		(effects
			(font
				(size 1.27 1.27)
			)
			(justify right bottom)
		)
	)
	(global_label "1V8_SYS"
		(shape input)
		(at 181.61 162.56 180)
		(fields_autoplaced yes)
		(effects
			(font
				(size 1.27 1.27)
			)
			(justify right)
		)
		(property "Intersheetrefs" "${INTERSHEET_REFS}"
			(at 171.3029 162.4806 0)
			(effects
				(font
					(size 1.27 1.27)
				)
				(justify right)
				(hide yes)
			)
		)
	)
	(global_label "1V8_SYS"
		(shape input)
		(at 181.61 68.58 180)
		(fields_autoplaced yes)
		(effects
			(font
				(size 1.27 1.27)
			)
			(justify right)
		)
		(property "Intersheetrefs" "${INTERSHEET_REFS}"
			(at 171.3029 68.5006 0)
			(effects
				(font
					(size 1.27 1.27)
				)
				(justify right)
				(hide yes)
			)
		)
	)
	(global_label "SDA"
		(shape input)
		(at 182.88 119.38 180)
		(fields_autoplaced yes)
		(effects
			(font
				(size 1.27 1.27)
			)
			(justify right)
		)
		(property "Intersheetrefs" "${INTERSHEET_REFS}"
			(at 176.9877 119.3006 0)
			(effects
				(font
					(size 1.27 1.27)
				)
				(justify right)
				(hide yes)
			)
		)
	)
	(global_label "SCL"
		(shape input)
		(at 177.8 176.53 180)
		(fields_autoplaced yes)
		(effects
			(font
				(size 1.27 1.27)
			)
			(justify right)
		)
		(property "Intersheetrefs" "${INTERSHEET_REFS}"
			(at 171.9682 176.4506 0)
			(effects
				(font
					(size 1.27 1.27)
				)
				(justify right)
				(hide yes)
			)
		)
	)
	(global_label "SDA"
		(shape input)
		(at 177.8 173.99 180)
		(fields_autoplaced yes)
		(effects
			(font
				(size 1.27 1.27)
			)
			(justify right)
		)
		(property "Intersheetrefs" "${INTERSHEET_REFS}"
			(at 171.9077 173.9106 0)
			(effects
				(font
					(size 1.27 1.27)
				)
				(justify right)
				(hide yes)
			)
		)
	)
	(global_label "1V8_SYS"
		(shape input)
		(at 182.88 114.3 180)
		(fields_autoplaced yes)
		(effects
			(font
				(size 1.27 1.27)
			)
			(justify right)
		)
		(property "Intersheetrefs" "${INTERSHEET_REFS}"
			(at 172.5729 114.2206 0)
			(effects
				(font
					(size 1.27 1.27)
				)
				(justify right)
				(hide yes)
			)
		)
	)
	(global_label "1V8_SYS"
		(shape input)
		(at 222.25 173.99 0)
		(fields_autoplaced yes)
		(effects
			(font
				(size 1.27 1.27)
			)
			(justify left)
		)
		(property "Intersheetrefs" "${INTERSHEET_REFS}"
			(at 232.5571 173.9106 0)
			(effects
				(font
					(size 1.27 1.27)
				)
				(justify left)
				(hide yes)
			)
		)
	)
	(global_label "1V8_SYS"
		(shape input)
		(at 250.825 173.99 180)
		(fields_autoplaced yes)
		(effects
			(font
				(size 1.27 1.27)
			)
			(justify right)
		)
		(property "Intersheetrefs" "${INTERSHEET_REFS}"
			(at 240.5179 173.9106 0)
			(effects
				(font
					(size 1.27 1.27)
				)
				(justify right)
				(hide yes)
			)
		)
	)
	(global_label "SCL"
		(shape input)
		(at 182.88 121.92 180)
		(fields_autoplaced yes)
		(effects
			(font
				(size 1.27 1.27)
			)
			(justify right)
		)
		(property "Intersheetrefs" "${INTERSHEET_REFS}"
			(at 177.0482 121.8406 0)
			(effects
				(font
					(size 1.27 1.27)
				)
				(justify right)
				(hide yes)
			)
		)
	)
	(symbol
		(lib_id "antmicroCapacitors0402:C_4u7_0402")
		(at 189.23 81.28 270)
		(unit 1)
		(exclude_from_sim no)
		(in_bom yes)
		(on_board yes)
		(dnp no)
		(fields_autoplaced yes)
		(property "Reference" "C34"
			(at 191.77 82.5563 90)
			(effects
				(font
					(size 1.27 1.27)
				)
				(justify left)
			)
		)
		(property "Value" "C_4u7_0402"
			(at 179.07 101.6 0)
			(effects
				(font
					(size 1.27 1.27)
					(thickness 0.15)
				)
				(justify left bottom)
				(hide yes)
			)
		)
		(property "Footprint" "antmicro-footprints:C_0402_1005Metric"
			(at 176.53 101.6 0)
			(effects
				(font
					(size 1.27 1.27)
					(thickness 0.15)
				)
				(justify left bottom)
				(hide yes)
			)
		)
		(property "Datasheet" " "
			(at 173.99 101.6 0)
			(effects
				(font
					(size 1.27 1.27)
					(thickness 0.15)
				)
				(justify left bottom)
				(hide yes)
			)
		)
		(property "Description" ""
			(at 189.23 81.28 0)
			(effects
				(font
					(size 1.27 1.27)
				)
			)
		)
		(property "Manufacturer" "Murata"
			(at 168.91 101.6 0)
			(effects
				(font
					(size 1.27 1.27)
					(thickness 0.15)
				)
				(justify left bottom)
				(hide yes)
			)
		)
		(property "MPN" "GRM155R61A475MEAAD"
			(at 171.45 101.6 0)
			(effects
				(font
					(size 1.27 1.27)
					(thickness 0.15)
				)
				(justify left bottom)
				(hide yes)
			)
		)
		(property "Val" "4u7"
			(at 191.77 85.7312 90)
			(effects
				(font
					(size 1.27 1.27)
					(thickness 0.15)
				)
				(justify left)
			)
		)
		(property "License" "Apache-2.0"
			(at 166.37 101.6 0)
			(effects
				(font
					(size 1.27 1.27)
					(thickness 0.15)
				)
				(justify left bottom)
				(hide yes)
			)
		)
		(property "Author" "Antmicro"
			(at 163.83 101.6 0)
			(effects
				(font
					(size 1.27 1.27)
					(thickness 0.15)
				)
				(justify left bottom)
				(hide yes)
			)
		)
		(property "Voltage" ""
			(at 161.29 101.6 0)
			(effects
				(font
					(size 1.27 1.27)
				)
				(justify left bottom)
				(hide yes)
			)
		)
		(property "Dielectric" ""
			(at 158.75 101.6 0)
			(effects
				(font
					(size 1.27 1.27)
				)
				(justify left bottom)
				(hide yes)
			)
		)
		(pin "1"
		)
		(pin "2"
		)
		(instances
			(project "ddr5-testbed"
				(path ""
					(reference "C34")
					(unit 1)
				)
			)
		)
	)
	(symbol
		(lib_id "antmicroCapacitors0402:C_4u7_0402")
		(at 226.695 81.28 270)
		(unit 1)
		(exclude_from_sim no)
		(in_bom yes)
		(on_board yes)
		(dnp no)
		(fields_autoplaced yes)
		(property "Reference" "C37"
			(at 229.235 82.5563 90)
			(effects
				(font
					(size 1.27 1.27)
				)
				(justify left)
			)
		)
		(property "Value" "C_4u7_0402"
			(at 216.535 101.6 0)
			(effects
				(font
					(size 1.27 1.27)
					(thickness 0.15)
				)
				(justify left bottom)
				(hide yes)
			)
		)
		(property "Footprint" "antmicro-footprints:C_0402_1005Metric"
			(at 213.995 101.6 0)
			(effects
				(font
					(size 1.27 1.27)
					(thickness 0.15)
				)
				(justify left bottom)
				(hide yes)
			)
		)
		(property "Datasheet" " "
			(at 211.455 101.6 0)
			(effects
				(font
					(size 1.27 1.27)
					(thickness 0.15)
				)
				(justify left bottom)
				(hide yes)
			)
		)
		(property "Description" ""
			(at 226.695 81.28 0)
			(effects
				(font
					(size 1.27 1.27)
				)
			)
		)
		(property "Manufacturer" "Murata"
			(at 206.375 101.6 0)
			(effects
				(font
					(size 1.27 1.27)
					(thickness 0.15)
				)
				(justify left bottom)
				(hide yes)
			)
		)
		(property "MPN" "GRM155R61A475MEAAD"
			(at 208.915 101.6 0)
			(effects
				(font
					(size 1.27 1.27)
					(thickness 0.15)
				)
				(justify left bottom)
				(hide yes)
			)
		)
		(property "Val" "4u7"
			(at 229.235 85.7312 90)
			(effects
				(font
					(size 1.27 1.27)
					(thickness 0.15)
				)
				(justify left)
			)
		)
		(property "License" "Apache-2.0"
			(at 203.835 101.6 0)
			(effects
				(font
					(size 1.27 1.27)
					(thickness 0.15)
				)
				(justify left bottom)
				(hide yes)
			)
		)
		(property "Author" "Antmicro"
			(at 201.295 101.6 0)
			(effects
				(font
					(size 1.27 1.27)
					(thickness 0.15)
				)
				(justify left bottom)
				(hide yes)
			)
		)
		(property "Voltage" ""
			(at 198.755 101.6 0)
			(effects
				(font
					(size 1.27 1.27)
				)
				(justify left bottom)
				(hide yes)
			)
		)
		(property "Dielectric" ""
			(at 196.215 101.6 0)
			(effects
				(font
					(size 1.27 1.27)
				)
				(justify left bottom)
				(hide yes)
			)
		)
		(pin "1"
		)
		(pin "2"
		)
		(instances
			(project "ddr5-testbed"
				(path ""
					(reference "C37")
					(unit 1)
				)
			)
		)
	)
	(symbol
		(lib_id "antmicroMemory:AT24CS01_SOT23")
		(at 198.12 173.99 0)
		(unit 1)
		(exclude_from_sim no)
		(in_bom yes)
		(on_board yes)
		(dnp no)
		(property "Reference" "IC2"
			(at 208.28 167.005 0)
			(effects
				(font
					(size 1.27 1.27)
				)
			)
		)
		(property "Value" "AT24CS01_SOT23"
			(at 208.28 168.91 0)
			(effects
				(font
					(size 1.27 1.27)
					(thickness 0.15)
				)
				(hide yes)
			)
		)
		(property "Footprint" "antmicro-footprints:SOT-23-5"
			(at 233.68 181.61 0)
			(effects
				(font
					(size 1.27 1.27)
					(thickness 0.15)
				)
				(justify left bottom)
				(hide yes)
			)
		)
		(property "Datasheet" "http://ww1.microchip.com/downloads/en/devicedoc/Atmel-8815-SEEPROM-AT24CS01-02-Datasheet.pdf"
			(at 233.68 184.15 0)
			(effects
				(font
					(size 1.27 1.27)
					(thickness 0.15)
				)
				(justify left bottom)
				(hide yes)
			)
		)
		(property "Description" ""
			(at 198.12 173.99 0)
			(effects
				(font
					(size 1.27 1.27)
				)
			)
		)
		(property "Manufacturer" "Atmel"
			(at 233.68 186.69 0)
			(effects
				(font
					(size 1.27 1.27)
					(thickness 0.15)
				)
				(justify left bottom)
				(hide yes)
			)
		)
		(property "MPN" "AT24CS01-ST"
			(at 208.28 169.545 0)
			(effects
				(font
					(size 1.27 1.27)
					(thickness 0.15)
				)
			)
		)
		(property "Author" "Antmicro"
			(at 233.68 191.77 0)
			(effects
				(font
					(size 1.27 1.27)
					(thickness 0.15)
				)
				(justify left bottom)
				(hide yes)
			)
		)
		(property "License" "Apache-2.0"
			(at 233.68 194.31 0)
			(effects
				(font
					(size 1.27 1.27)
					(thickness 0.15)
				)
				(justify left bottom)
				(hide yes)
			)
		)
		(pin "1"
		)
		(pin "2"
		)
		(pin "3"
		)
		(pin "4"
		)
		(pin "5"
		)
		(instances
			(project "ddr5-testbed"
				(path ""
					(reference "IC2")
					(unit 1)
				)
			)
		)
	)
	(symbol
		(lib_id "antmicroResistors0402:R_0R_0402")
		(at 207.645 68.58 0)
		(unit 1)
		(exclude_from_sim no)
		(in_bom no)
		(on_board yes)
		(dnp yes)
		(property "Reference" "R8"
			(at 210.185 60.96 0)
			(effects
				(font
					(size 1.27 1.27)
				)
			)
		)
		(property "Value" "R_0R_0402"
			(at 227.965 81.28 0)
			(effects
				(font
					(size 1.27 1.27)
					(thickness 0.15)
				)
				(justify left bottom)
				(hide yes)
			)
		)
		(property "Footprint" "antmicro-footprints:R_0402_1005Metric"
			(at 227.965 83.82 0)
			(effects
				(font
					(size 1.27 1.27)
					(thickness 0.15)
				)
				(justify left bottom)
				(hide yes)
			)
		)
		(property "Datasheet" "https://industrial.panasonic.com/cdbs/www-data/pdf/RDA0000/AOA0000C301.pdf"
			(at 227.965 86.36 0)
			(effects
				(font
					(size 1.27 1.27)
					(thickness 0.15)
				)
				(justify left bottom)
				(hide yes)
			)
		)
		(property "Description" ""
			(at 207.645 68.58 0)
			(effects
				(font
					(size 1.27 1.27)
				)
			)
		)
		(property "Manufacturer" "Panasonic"
			(at 227.965 91.44 0)
			(effects
				(font
					(size 1.27 1.27)
					(thickness 0.15)
				)
				(justify left bottom)
				(hide yes)
			)
		)
		(property "MPN" "ERJ2GE0R00X"
			(at 227.965 88.9 0)
			(effects
				(font
					(size 1.27 1.27)
					(thickness 0.15)
				)
				(justify left bottom)
				(hide yes)
			)
		)
		(property "Val" "0R"
			(at 210.185 63.5 0)
			(effects
				(font
					(size 1.27 1.27)
					(thickness 0.15)
				)
			)
		)
		(property "License" "Apache-2.0"
			(at 227.965 93.98 0)
			(effects
				(font
					(size 1.27 1.27)
					(thickness 0.15)
				)
				(justify left bottom)
				(hide yes)
			)
		)
		(property "Author" "Antmicro"
			(at 227.965 96.52 0)
			(effects
				(font
					(size 1.27 1.27)
					(thickness 0.15)
				)
				(justify left bottom)
				(hide yes)
			)
		)
		(property "Tolerance" "~"
			(at 227.965 78.74 0)
			(effects
				(font
					(size 1.27 1.27)
				)
				(justify left bottom)
				(hide yes)
			)
		)
		(property "Current" "1A"
			(at 227.965 99.06 0)
			(effects
				(font
					(size 1.27 1.27)
					(thickness 0.15)
				)
				(justify left bottom)
				(hide yes)
			)
		)
		(pin "1"
		)
		(pin "2"
		)
		(instances
			(project "ddr5-testbed"
				(path ""
					(reference "R8")
					(unit 1)
				)
			)
		)
	)
	(symbol
		(lib_id "antmicropower:GND")
		(at 189.23 86.36 0)
		(unit 1)
		(exclude_from_sim no)
		(in_bom yes)
		(on_board yes)
		(dnp no)
		(fields_autoplaced yes)
		(property "Reference" "#PWR0106"
			(at 189.23 92.71 0)
			(effects
				(font
					(size 1.27 1.27)
				)
				(hide yes)
			)
		)
		(property "Value" "GND"
			(at 189.23 90.805 0)
			(effects
				(font
					(size 1.27 1.27)
				)
			)
		)
		(property "Footprint" ""
			(at 189.23 86.36 0)
			(effects
				(font
					(size 1.27 1.27)
				)
				(hide yes)
			)
		)
		(property "Datasheet" ""
			(at 189.23 86.36 0)
			(effects
				(font
					(size 1.27 1.27)
				)
				(hide yes)
			)
		)
		(property "Description" ""
			(at 189.23 86.36 0)
			(effects
				(font
					(size 1.27 1.27)
				)
			)
		)
		(pin "1"
		)
		(instances
			(project "ddr5-testbed"
				(path ""
					(reference "#PWR0106")
					(unit 1)
				)
			)
		)
	)
	(symbol
		(lib_id "antmicropower:GND")
		(at 226.695 86.36 0)
		(unit 1)
		(exclude_from_sim no)
		(in_bom yes)
		(on_board yes)
		(dnp no)
		(fields_autoplaced yes)
		(property "Reference" "#PWR0107"
			(at 226.695 92.71 0)
			(effects
				(font
					(size 1.27 1.27)
				)
				(hide yes)
			)
		)
		(property "Value" "GND"
			(at 226.695 90.805 0)
			(effects
				(font
					(size 1.27 1.27)
				)
			)
		)
		(property "Footprint" ""
			(at 226.695 86.36 0)
			(effects
				(font
					(size 1.27 1.27)
				)
				(hide yes)
			)
		)
		(property "Datasheet" ""
			(at 226.695 86.36 0)
			(effects
				(font
					(size 1.27 1.27)
				)
				(hide yes)
			)
		)
		(property "Description" ""
			(at 226.695 86.36 0)
			(effects
				(font
					(size 1.27 1.27)
				)
			)
		)
		(pin "1"
		)
		(instances
			(project "ddr5-testbed"
				(path ""
					(reference "#PWR0107")
					(unit 1)
				)
			)
		)
	)
	(symbol
		(lib_id "antmicropower:GND")
		(at 219.71 86.36 0)
		(unit 1)
		(exclude_from_sim no)
		(in_bom yes)
		(on_board yes)
		(dnp no)
		(fields_autoplaced yes)
		(property "Reference" "#PWR0108"
			(at 219.71 92.71 0)
			(effects
				(font
					(size 1.27 1.27)
				)
				(hide yes)
			)
		)
		(property "Value" "GND"
			(at 219.71 91.44 0)
			(effects
				(font
					(size 1.27 1.27)
				)
			)
		)
		(property "Footprint" ""
			(at 219.71 86.36 0)
			(effects
				(font
					(size 1.27 1.27)
				)
				(hide yes)
			)
		)
		(property "Datasheet" ""
			(at 219.71 86.36 0)
			(effects
				(font
					(size 1.27 1.27)
				)
				(hide yes)
			)
		)
		(property "Description" ""
			(at 219.71 86.36 0)
			(effects
				(font
					(size 1.27 1.27)
				)
			)
		)
		(pin "1"
		)
		(instances
			(project "ddr5-testbed"
				(path ""
					(reference "#PWR0108")
					(unit 1)
				)
			)
		)
	)
	(symbol
		(lib_id "antmicroResistors0402:R_10k_0402")
		(at 182.88 165.735 270)
		(unit 1)
		(exclude_from_sim no)
		(in_bom yes)
		(on_board yes)
		(dnp no)
		(fields_autoplaced yes)
		(property "Reference" "R13"
			(at 185.42 167.005 90)
			(effects
				(font
					(size 1.27 1.27)
				)
				(justify left)
			)
		)
		(property "Value" "R_10k_0402"
			(at 170.18 186.055 0)
			(effects
				(font
					(size 1.27 1.27)
					(thickness 0.15)
				)
				(justify left bottom)
				(hide yes)
			)
		)
		(property "Footprint" "antmicro-footprints:R_0402_1005Metric"
			(at 167.64 186.055 0)
			(effects
				(font
					(size 1.27 1.27)
					(thickness 0.15)
				)
				(justify left bottom)
				(hide yes)
			)
		)
		(property "Datasheet" "https://www.bourns.com/docs/product-datasheets/cr.pdf"
			(at 165.1 186.055 0)
			(effects
				(font
					(size 1.27 1.27)
					(thickness 0.15)
				)
				(justify left bottom)
				(hide yes)
			)
		)
		(property "Description" ""
			(at 182.88 165.735 0)
			(effects
				(font
					(size 1.27 1.27)
				)
			)
		)
		(property "Manufacturer" "Bourns"
			(at 160.02 186.055 0)
			(effects
				(font
					(size 1.27 1.27)
					(thickness 0.15)
				)
				(justify left bottom)
				(hide yes)
			)
		)
		(property "MPN" "CR0402-FX-1002GLF"
			(at 162.56 186.055 0)
			(effects
				(font
					(size 1.27 1.27)
					(thickness 0.15)
				)
				(justify left bottom)
				(hide yes)
			)
		)
		(property "Val" "10k"
			(at 185.42 170.1799 90)
			(effects
				(font
					(size 1.27 1.27)
					(thickness 0.15)
				)
				(justify left)
			)
		)
		(property "License" "Apache-2.0"
			(at 157.48 186.055 0)
			(effects
				(font
					(size 1.27 1.27)
					(thickness 0.15)
				)
				(justify left bottom)
				(hide yes)
			)
		)
		(property "Author" "Antmicro"
			(at 154.94 186.055 0)
			(effects
				(font
					(size 1.27 1.27)
					(thickness 0.15)
				)
				(justify left bottom)
				(hide yes)
			)
		)
		(property "Tolerance" "1%"
			(at 172.72 186.055 0)
			(effects
				(font
					(size 1.27 1.27)
				)
				(justify left bottom)
				(hide yes)
			)
		)
		(pin "1"
		)
		(pin "2"
		)
		(instances
			(project "ddr5-testbed"
				(path ""
					(reference "R13")
					(unit 1)
				)
			)
		)
	)
	(symbol
		(lib_id "antmicroResistors0402:R_220R_0402")
		(at 226.06 111.76 0)
		(unit 1)
		(exclude_from_sim no)
		(in_bom yes)
		(on_board yes)
		(dnp no)
		(property "Reference" "R9"
			(at 223.52 110.49 0)
			(effects
				(font
					(size 1.27 1.27)
				)
			)
		)
		(property "Value" "R_220R_0402"
			(at 246.38 124.46 0)
			(effects
				(font
					(size 1.27 1.27)
					(thickness 0.15)
				)
				(justify left bottom)
				(hide yes)
			)
		)
		(property "Footprint" "antmicro-footprints:R_0402_1005Metric"
			(at 246.38 127 0)
			(effects
				(font
					(size 1.27 1.27)
					(thickness 0.15)
				)
				(justify left bottom)
				(hide yes)
			)
		)
		(property "Datasheet" "https://www.bourns.com/docs/product-datasheets/cr.pdf"
			(at 246.38 129.54 0)
			(effects
				(font
					(size 1.27 1.27)
					(thickness 0.15)
				)
				(justify left bottom)
				(hide yes)
			)
		)
		(property "Description" ""
			(at 226.06 111.76 0)
			(effects
				(font
					(size 1.27 1.27)
				)
			)
		)
		(property "Manufacturer" "Bourns"
			(at 246.38 134.62 0)
			(effects
				(font
					(size 1.27 1.27)
					(thickness 0.15)
				)
				(justify left bottom)
				(hide yes)
			)
		)
		(property "MPN" "CR0402-FX-2200GLF"
			(at 246.38 132.08 0)
			(effects
				(font
					(size 1.27 1.27)
					(thickness 0.15)
				)
				(justify left bottom)
				(hide yes)
			)
		)
		(property "Val" "220R"
			(at 233.68 110.49 0)
			(effects
				(font
					(size 1.27 1.27)
					(thickness 0.15)
				)
			)
		)
		(property "License" "Apache-2.0"
			(at 246.38 137.16 0)
			(effects
				(font
					(size 1.27 1.27)
					(thickness 0.15)
				)
				(justify left bottom)
				(hide yes)
			)
		)
		(property "Author" "Antmicro"
			(at 246.38 139.7 0)
			(effects
				(font
					(size 1.27 1.27)
					(thickness 0.15)
				)
				(justify left bottom)
				(hide yes)
			)
		)
		(property "Tolerance" "1%"
			(at 246.38 121.92 0)
			(effects
				(font
					(size 1.27 1.27)
				)
				(justify left bottom)
				(hide yes)
			)
		)
		(pin "1"
		)
		(pin "2"
		)
		(instances
			(project "ddr5-testbed"
				(path ""
					(reference "R9")
					(unit 1)
				)
			)
		)
	)
	(symbol
		(lib_id "antmicroResistors0402:R_220R_0402")
		(at 226.06 114.3 0)
		(unit 1)
		(exclude_from_sim no)
		(in_bom yes)
		(on_board yes)
		(dnp no)
		(property "Reference" "R10"
			(at 224.155 113.03 0)
			(effects
				(font
					(size 1.27 1.27)
				)
			)
		)
		(property "Value" "R_220R_0402"
			(at 246.38 127 0)
			(effects
				(font
					(size 1.27 1.27)
					(thickness 0.15)
				)
				(justify left bottom)
				(hide yes)
			)
		)
		(property "Footprint" "antmicro-footprints:R_0402_1005Metric"
			(at 246.38 129.54 0)
			(effects
				(font
					(size 1.27 1.27)
					(thickness 0.15)
				)
				(justify left bottom)
				(hide yes)
			)
		)
		(property "Datasheet" "https://www.bourns.com/docs/product-datasheets/cr.pdf"
			(at 246.38 132.08 0)
			(effects
				(font
					(size 1.27 1.27)
					(thickness 0.15)
				)
				(justify left bottom)
				(hide yes)
			)
		)
		(property "Description" ""
			(at 226.06 114.3 0)
			(effects
				(font
					(size 1.27 1.27)
				)
			)
		)
		(property "Manufacturer" "Bourns"
			(at 246.38 137.16 0)
			(effects
				(font
					(size 1.27 1.27)
					(thickness 0.15)
				)
				(justify left bottom)
				(hide yes)
			)
		)
		(property "MPN" "CR0402-FX-2200GLF"
			(at 246.38 134.62 0)
			(effects
				(font
					(size 1.27 1.27)
					(thickness 0.15)
				)
				(justify left bottom)
				(hide yes)
			)
		)
		(property "Val" "220R"
			(at 233.68 113.03 0)
			(effects
				(font
					(size 1.27 1.27)
					(thickness 0.15)
				)
			)
		)
		(property "License" "Apache-2.0"
			(at 246.38 139.7 0)
			(effects
				(font
					(size 1.27 1.27)
					(thickness 0.15)
				)
				(justify left bottom)
				(hide yes)
			)
		)
		(property "Author" "Antmicro"
			(at 246.38 142.24 0)
			(effects
				(font
					(size 1.27 1.27)
					(thickness 0.15)
				)
				(justify left bottom)
				(hide yes)
			)
		)
		(property "Tolerance" "1%"
			(at 246.38 124.46 0)
			(effects
				(font
					(size 1.27 1.27)
				)
				(justify left bottom)
				(hide yes)
			)
		)
		(pin "1"
		)
		(pin "2"
		)
		(instances
			(project "ddr5-testbed"
				(path ""
					(reference "R10")
					(unit 1)
				)
			)
		)
	)
	(symbol
		(lib_id "antmicroResistors0402:R_220R_0402")
		(at 226.06 116.84 0)
		(unit 1)
		(exclude_from_sim no)
		(in_bom yes)
		(on_board yes)
		(dnp no)
		(property "Reference" "R11"
			(at 224.155 115.57 0)
			(effects
				(font
					(size 1.27 1.27)
				)
			)
		)
		(property "Value" "R_220R_0402"
			(at 246.38 129.54 0)
			(effects
				(font
					(size 1.27 1.27)
					(thickness 0.15)
				)
				(justify left bottom)
				(hide yes)
			)
		)
		(property "Footprint" "antmicro-footprints:R_0402_1005Metric"
			(at 246.38 132.08 0)
			(effects
				(font
					(size 1.27 1.27)
					(thickness 0.15)
				)
				(justify left bottom)
				(hide yes)
			)
		)
		(property "Datasheet" "https://www.bourns.com/docs/product-datasheets/cr.pdf"
			(at 246.38 134.62 0)
			(effects
				(font
					(size 1.27 1.27)
					(thickness 0.15)
				)
				(justify left bottom)
				(hide yes)
			)
		)
		(property "Description" ""
			(at 226.06 116.84 0)
			(effects
				(font
					(size 1.27 1.27)
				)
			)
		)
		(property "Manufacturer" "Bourns"
			(at 246.38 139.7 0)
			(effects
				(font
					(size 1.27 1.27)
					(thickness 0.15)
				)
				(justify left bottom)
				(hide yes)
			)
		)
		(property "MPN" "CR0402-FX-2200GLF"
			(at 246.38 137.16 0)
			(effects
				(font
					(size 1.27 1.27)
					(thickness 0.15)
				)
				(justify left bottom)
				(hide yes)
			)
		)
		(property "Val" "220R"
			(at 233.68 115.57 0)
			(effects
				(font
					(size 1.27 1.27)
					(thickness 0.15)
				)
			)
		)
		(property "License" "Apache-2.0"
			(at 246.38 142.24 0)
			(effects
				(font
					(size 1.27 1.27)
					(thickness 0.15)
				)
				(justify left bottom)
				(hide yes)
			)
		)
		(property "Author" "Antmicro"
			(at 246.38 144.78 0)
			(effects
				(font
					(size 1.27 1.27)
					(thickness 0.15)
				)
				(justify left bottom)
				(hide yes)
			)
		)
		(property "Tolerance" "1%"
			(at 246.38 127 0)
			(effects
				(font
					(size 1.27 1.27)
				)
				(justify left bottom)
				(hide yes)
			)
		)
		(pin "1"
		)
		(pin "2"
		)
		(instances
			(project "ddr5-testbed"
				(path ""
					(reference "R11")
					(unit 1)
				)
			)
		)
	)
	(symbol
		(lib_id "antmicroLEDIndicationDiscrete:LED_G_0603_KP-1608CGCK")
		(at 237.49 120.65 270)
		(unit 1)
		(exclude_from_sim no)
		(in_bom yes)
		(on_board yes)
		(dnp no)
		(property "Reference" "D4"
			(at 238.125 121.92 90)
			(effects
				(font
					(size 1.27 1.27)
				)
				(justify left)
			)
		)
		(property "Value" "LED_G_0603_KP-1608CGCK"
			(at 241.3 126.3649 90)
			(effects
				(font
					(size 1.27 1.27)
					(thickness 0.15)
				)
				(justify left)
				(hide yes)
			)
		)
		(property "Footprint" "antmicro-footprints:LED_0603_1608Metric_G"
			(at 227.33 143.51 0)
			(effects
				(font
					(size 1.27 1.27)
					(thickness 0.15)
				)
				(justify left bottom)
				(hide yes)
			)
		)
		(property "Datasheet" "http://www.farnell.com/datasheets/2045956.pdf"
			(at 224.79 143.51 0)
			(effects
				(font
					(size 1.27 1.27)
					(thickness 0.15)
				)
				(justify left bottom)
				(hide yes)
			)
		)
		(property "Description" ""
			(at 237.49 120.65 0)
			(effects
				(font
					(size 1.27 1.27)
				)
			)
		)
		(property "MPN" "KP-1608CGCK"
			(at 239.395 126.365 0)
			(effects
				(font
					(size 1.27 1.27)
					(thickness 0.15)
				)
				(justify left)
			)
		)
		(property "Manufacturer" "Kingbright"
			(at 219.71 143.51 0)
			(effects
				(font
					(size 1.27 1.27)
					(thickness 0.15)
				)
				(justify left bottom)
				(hide yes)
			)
		)
		(property "Author" "Antmicro"
			(at 217.17 143.51 0)
			(effects
				(font
					(size 1.27 1.27)
					(thickness 0.15)
				)
				(justify left bottom)
				(hide yes)
			)
		)
		(property "License" "Apache-2.0"
			(at 214.63 143.51 0)
			(effects
				(font
					(size 1.27 1.27)
					(thickness 0.15)
				)
				(justify left bottom)
				(hide yes)
			)
		)
		(pin "1"
		)
		(pin "2"
		)
		(instances
			(project "ddr5-testbed"
				(path ""
					(reference "D4")
					(unit 1)
				)
			)
		)
	)
	(symbol
		(lib_id "antmicroResistors0402:R_220R_0402")
		(at 226.06 119.38 0)
		(unit 1)
		(exclude_from_sim no)
		(in_bom yes)
		(on_board yes)
		(dnp no)
		(property "Reference" "R12"
			(at 224.155 118.11 0)
			(effects
				(font
					(size 1.27 1.27)
				)
			)
		)
		(property "Value" "R_220R_0402"
			(at 246.38 132.08 0)
			(effects
				(font
					(size 1.27 1.27)
					(thickness 0.15)
				)
				(justify left bottom)
				(hide yes)
			)
		)
		(property "Footprint" "antmicro-footprints:R_0402_1005Metric"
			(at 246.38 134.62 0)
			(effects
				(font
					(size 1.27 1.27)
					(thickness 0.15)
				)
				(justify left bottom)
				(hide yes)
			)
		)
		(property "Datasheet" "https://www.bourns.com/docs/product-datasheets/cr.pdf"
			(at 246.38 137.16 0)
			(effects
				(font
					(size 1.27 1.27)
					(thickness 0.15)
				)
				(justify left bottom)
				(hide yes)
			)
		)
		(property "Description" ""
			(at 226.06 119.38 0)
			(effects
				(font
					(size 1.27 1.27)
				)
			)
		)
		(property "Manufacturer" "Bourns"
			(at 246.38 142.24 0)
			(effects
				(font
					(size 1.27 1.27)
					(thickness 0.15)
				)
				(justify left bottom)
				(hide yes)
			)
		)
		(property "MPN" "CR0402-FX-2200GLF"
			(at 246.38 139.7 0)
			(effects
				(font
					(size 1.27 1.27)
					(thickness 0.15)
				)
				(justify left bottom)
				(hide yes)
			)
		)
		(property "Val" "220R"
			(at 233.68 118.11 0)
			(effects
				(font
					(size 1.27 1.27)
					(thickness 0.15)
				)
			)
		)
		(property "License" "Apache-2.0"
			(at 246.38 144.78 0)
			(effects
				(font
					(size 1.27 1.27)
					(thickness 0.15)
				)
				(justify left bottom)
				(hide yes)
			)
		)
		(property "Author" "Antmicro"
			(at 246.38 147.32 0)
			(effects
				(font
					(size 1.27 1.27)
					(thickness 0.15)
				)
				(justify left bottom)
				(hide yes)
			)
		)
		(property "Tolerance" "1%"
			(at 246.38 129.54 0)
			(effects
				(font
					(size 1.27 1.27)
				)
				(justify left bottom)
				(hide yes)
			)
		)
		(pin "1"
		)
		(pin "2"
		)
		(instances
			(project "ddr5-testbed"
				(path ""
					(reference "R12")
					(unit 1)
				)
			)
		)
	)
	(symbol
		(lib_id "antmicroCapacitors0402:C_100n_0402")
		(at 252.095 175.26 270)
		(unit 1)
		(exclude_from_sim no)
		(in_bom yes)
		(on_board yes)
		(dnp no)
		(property "Reference" "C38"
			(at 252.73 175.895 90)
			(effects
				(font
					(size 1.27 1.27)
				)
				(justify left)
			)
		)
		(property "Value" "C_100n_0402"
			(at 241.935 195.58 0)
			(effects
				(font
					(size 1.27 1.27)
					(thickness 0.15)
				)
				(justify left bottom)
				(hide yes)
			)
		)
		(property "Footprint" "antmicro-footprints:C_0402_1005Metric"
			(at 239.395 195.58 0)
			(effects
				(font
					(size 1.27 1.27)
					(thickness 0.15)
				)
				(justify left bottom)
				(hide yes)
			)
		)
		(property "Datasheet" "https://search.murata.co.jp/Ceramy/image/img/A01X/G101/ENG/GRM155R61H104KE14-01.pdf"
			(at 236.855 195.58 0)
			(effects
				(font
					(size 1.27 1.27)
					(thickness 0.15)
				)
				(justify left bottom)
				(hide yes)
			)
		)
		(property "Description" ""
			(at 252.095 175.26 0)
			(effects
				(font
					(size 1.27 1.27)
				)
			)
		)
		(property "Manufacturer" "Murata"
			(at 231.775 195.58 0)
			(effects
				(font
					(size 1.27 1.27)
					(thickness 0.15)
				)
				(justify left bottom)
				(hide yes)
			)
		)
		(property "MPN" "GRM155R61H104KE14D"
			(at 234.315 195.58 0)
			(effects
				(font
					(size 1.27 1.27)
					(thickness 0.15)
				)
				(justify left bottom)
				(hide yes)
			)
		)
		(property "Val" "100n"
			(at 252.73 179.705 90)
			(effects
				(font
					(size 1.27 1.27)
					(thickness 0.15)
				)
				(justify left)
			)
		)
		(property "License" "Apache-2.0"
			(at 229.235 195.58 0)
			(effects
				(font
					(size 1.27 1.27)
					(thickness 0.15)
				)
				(justify left bottom)
				(hide yes)
			)
		)
		(property "Author" "Antmicro"
			(at 226.695 195.58 0)
			(effects
				(font
					(size 1.27 1.27)
					(thickness 0.15)
				)
				(justify left bottom)
				(hide yes)
			)
		)
		(property "Voltage" "50V"
			(at 224.155 195.58 0)
			(effects
				(font
					(size 1.27 1.27)
				)
				(justify left bottom)
				(hide yes)
			)
		)
		(property "Dielectric" "X5R"
			(at 221.615 195.58 0)
			(effects
				(font
					(size 1.27 1.27)
				)
				(justify left bottom)
				(hide yes)
			)
		)
		(pin "1"
		)
		(pin "2"
		)
		(instances
			(project "ddr5-testbed"
				(path ""
					(reference "C38")
					(unit 1)
				)
			)
		)
	)
	(symbol
		(lib_id "antmicroLEDIndicationDiscrete:LED_G_0603_KP-1608CGCK")
		(at 245.11 120.65 270)
		(unit 1)
		(exclude_from_sim no)
		(in_bom yes)
		(on_board yes)
		(dnp no)
		(property "Reference" "D3"
			(at 245.745 121.92 90)
			(effects
				(font
					(size 1.27 1.27)
				)
				(justify left)
			)
		)
		(property "Value" "LED_G_0603_KP-1608CGCK"
			(at 248.92 126.3649 90)
			(effects
				(font
					(size 1.27 1.27)
					(thickness 0.15)
				)
				(justify left)
				(hide yes)
			)
		)
		(property "Footprint" "antmicro-footprints:LED_0603_1608Metric_G"
			(at 234.95 143.51 0)
			(effects
				(font
					(size 1.27 1.27)
					(thickness 0.15)
				)
				(justify left bottom)
				(hide yes)
			)
		)
		(property "Datasheet" "http://www.farnell.com/datasheets/2045956.pdf"
			(at 232.41 143.51 0)
			(effects
				(font
					(size 1.27 1.27)
					(thickness 0.15)
				)
				(justify left bottom)
				(hide yes)
			)
		)
		(property "Description" ""
			(at 245.11 120.65 0)
			(effects
				(font
					(size 1.27 1.27)
				)
			)
		)
		(property "MPN" "KP-1608CGCK"
			(at 247.015 126.365 0)
			(effects
				(font
					(size 1.27 1.27)
					(thickness 0.15)
				)
				(justify left)
			)
		)
		(property "Manufacturer" "Kingbright"
			(at 227.33 143.51 0)
			(effects
				(font
					(size 1.27 1.27)
					(thickness 0.15)
				)
				(justify left bottom)
				(hide yes)
			)
		)
		(property "Author" "Antmicro"
			(at 224.79 143.51 0)
			(effects
				(font
					(size 1.27 1.27)
					(thickness 0.15)
				)
				(justify left bottom)
				(hide yes)
			)
		)
		(property "License" "Apache-2.0"
			(at 222.25 143.51 0)
			(effects
				(font
					(size 1.27 1.27)
					(thickness 0.15)
				)
				(justify left bottom)
				(hide yes)
			)
		)
		(pin "1"
		)
		(pin "2"
		)
		(instances
			(project "ddr5-testbed"
				(path ""
					(reference "D3")
					(unit 1)
				)
			)
		)
	)
	(symbol
		(lib_id "antmicroLEDIndicationDiscrete:LED_G_0603_KP-1608CGCK")
		(at 252.73 120.65 270)
		(unit 1)
		(exclude_from_sim no)
		(in_bom yes)
		(on_board yes)
		(dnp no)
		(property "Reference" "D2"
			(at 253.365 121.92 90)
			(effects
				(font
					(size 1.27 1.27)
				)
				(justify left)
			)
		)
		(property "Value" "LED_G_0603_KP-1608CGCK"
			(at 256.54 126.3649 90)
			(effects
				(font
					(size 1.27 1.27)
					(thickness 0.15)
				)
				(justify left)
				(hide yes)
			)
		)
		(property "Footprint" "antmicro-footprints:LED_0603_1608Metric_G"
			(at 242.57 143.51 0)
			(effects
				(font
					(size 1.27 1.27)
					(thickness 0.15)
				)
				(justify left bottom)
				(hide yes)
			)
		)
		(property "Datasheet" "http://www.farnell.com/datasheets/2045956.pdf"
			(at 240.03 143.51 0)
			(effects
				(font
					(size 1.27 1.27)
					(thickness 0.15)
				)
				(justify left bottom)
				(hide yes)
			)
		)
		(property "Description" ""
			(at 252.73 120.65 0)
			(effects
				(font
					(size 1.27 1.27)
				)
			)
		)
		(property "MPN" "KP-1608CGCK"
			(at 254.635 126.365 0)
			(effects
				(font
					(size 1.27 1.27)
					(thickness 0.15)
				)
				(justify left)
			)
		)
		(property "Manufacturer" "Kingbright"
			(at 234.95 143.51 0)
			(effects
				(font
					(size 1.27 1.27)
					(thickness 0.15)
				)
				(justify left bottom)
				(hide yes)
			)
		)
		(property "Author" "Antmicro"
			(at 232.41 143.51 0)
			(effects
				(font
					(size 1.27 1.27)
					(thickness 0.15)
				)
				(justify left bottom)
				(hide yes)
			)
		)
		(property "License" "Apache-2.0"
			(at 229.87 143.51 0)
			(effects
				(font
					(size 1.27 1.27)
					(thickness 0.15)
				)
				(justify left bottom)
				(hide yes)
			)
		)
		(pin "1"
		)
		(pin "2"
		)
		(instances
			(project "ddr5-testbed"
				(path ""
					(reference "D2")
					(unit 1)
				)
			)
		)
	)
	(symbol
		(lib_id "antmicroLEDIndicationDiscrete:LED_G_0603_KP-1608CGCK")
		(at 260.35 120.65 270)
		(unit 1)
		(exclude_from_sim no)
		(in_bom yes)
		(on_board yes)
		(dnp no)
		(property "Reference" "D1"
			(at 260.985 121.92 90)
			(effects
				(font
					(size 1.27 1.27)
				)
				(justify left)
			)
		)
		(property "Value" "LED_G_0603_KP-1608CGCK"
			(at 264.16 126.3649 90)
			(effects
				(font
					(size 1.27 1.27)
					(thickness 0.15)
				)
				(justify left)
				(hide yes)
			)
		)
		(property "Footprint" "antmicro-footprints:LED_0603_1608Metric_G"
			(at 250.19 143.51 0)
			(effects
				(font
					(size 1.27 1.27)
					(thickness 0.15)
				)
				(justify left bottom)
				(hide yes)
			)
		)
		(property "Datasheet" "http://www.farnell.com/datasheets/2045956.pdf"
			(at 247.65 143.51 0)
			(effects
				(font
					(size 1.27 1.27)
					(thickness 0.15)
				)
				(justify left bottom)
				(hide yes)
			)
		)
		(property "Description" ""
			(at 260.35 120.65 0)
			(effects
				(font
					(size 1.27 1.27)
				)
			)
		)
		(property "MPN" "KP-1608CGCK"
			(at 262.255 126.365 0)
			(effects
				(font
					(size 1.27 1.27)
					(thickness 0.15)
				)
				(justify left)
			)
		)
		(property "Manufacturer" "Kingbright"
			(at 242.57 143.51 0)
			(effects
				(font
					(size 1.27 1.27)
					(thickness 0.15)
				)
				(justify left bottom)
				(hide yes)
			)
		)
		(property "Author" "Antmicro"
			(at 240.03 143.51 0)
			(effects
				(font
					(size 1.27 1.27)
					(thickness 0.15)
				)
				(justify left bottom)
				(hide yes)
			)
		)
		(property "License" "Apache-2.0"
			(at 237.49 143.51 0)
			(effects
				(font
					(size 1.27 1.27)
					(thickness 0.15)
				)
				(justify left bottom)
				(hide yes)
			)
		)
		(pin "1"
		)
		(pin "2"
		)
		(instances
			(project "ddr5-testbed"
				(path ""
					(reference "D1")
					(unit 1)
				)
			)
		)
	)
	(symbol
		(lib_id "antmicropower:GND")
		(at 237.49 139.7 0)
		(unit 1)
		(exclude_from_sim no)
		(in_bom yes)
		(on_board yes)
		(dnp no)
		(fields_autoplaced yes)
		(property "Reference" "#PWR0109"
			(at 237.49 146.05 0)
			(effects
				(font
					(size 1.27 1.27)
				)
				(hide yes)
			)
		)
		(property "Value" "GND"
			(at 237.49 144.78 0)
			(effects
				(font
					(size 1.27 1.27)
				)
			)
		)
		(property "Footprint" ""
			(at 237.49 139.7 0)
			(effects
				(font
					(size 1.27 1.27)
				)
				(hide yes)
			)
		)
		(property "Datasheet" ""
			(at 237.49 139.7 0)
			(effects
				(font
					(size 1.27 1.27)
				)
				(hide yes)
			)
		)
		(property "Description" ""
			(at 237.49 139.7 0)
			(effects
				(font
					(size 1.27 1.27)
				)
			)
		)
		(pin "1"
		)
		(instances
			(project "ddr5-testbed"
				(path ""
					(reference "#PWR0109")
					(unit 1)
				)
			)
		)
	)
	(symbol
		(lib_id "antmicropower:GND")
		(at 245.11 139.7 0)
		(unit 1)
		(exclude_from_sim no)
		(in_bom yes)
		(on_board yes)
		(dnp no)
		(fields_autoplaced yes)
		(property "Reference" "#PWR0110"
			(at 245.11 146.05 0)
			(effects
				(font
					(size 1.27 1.27)
				)
				(hide yes)
			)
		)
		(property "Value" "GND"
			(at 245.11 144.78 0)
			(effects
				(font
					(size 1.27 1.27)
				)
			)
		)
		(property "Footprint" ""
			(at 245.11 139.7 0)
			(effects
				(font
					(size 1.27 1.27)
				)
				(hide yes)
			)
		)
		(property "Datasheet" ""
			(at 245.11 139.7 0)
			(effects
				(font
					(size 1.27 1.27)
				)
				(hide yes)
			)
		)
		(property "Description" ""
			(at 245.11 139.7 0)
			(effects
				(font
					(size 1.27 1.27)
				)
			)
		)
		(pin "1"
		)
		(instances
			(project "ddr5-testbed"
				(path ""
					(reference "#PWR0110")
					(unit 1)
				)
			)
		)
	)
	(symbol
		(lib_id "antmicropower:GND")
		(at 252.73 139.7 0)
		(unit 1)
		(exclude_from_sim no)
		(in_bom yes)
		(on_board yes)
		(dnp no)
		(fields_autoplaced yes)
		(property "Reference" "#PWR0111"
			(at 252.73 146.05 0)
			(effects
				(font
					(size 1.27 1.27)
				)
				(hide yes)
			)
		)
		(property "Value" "GND"
			(at 252.73 144.78 0)
			(effects
				(font
					(size 1.27 1.27)
				)
			)
		)
		(property "Footprint" ""
			(at 252.73 139.7 0)
			(effects
				(font
					(size 1.27 1.27)
				)
				(hide yes)
			)
		)
		(property "Datasheet" ""
			(at 252.73 139.7 0)
			(effects
				(font
					(size 1.27 1.27)
				)
				(hide yes)
			)
		)
		(property "Description" ""
			(at 252.73 139.7 0)
			(effects
				(font
					(size 1.27 1.27)
				)
			)
		)
		(pin "1"
		)
		(instances
			(project "ddr5-testbed"
				(path ""
					(reference "#PWR0111")
					(unit 1)
				)
			)
		)
	)
	(symbol
		(lib_id "antmicropower:GND")
		(at 260.35 139.7 0)
		(unit 1)
		(exclude_from_sim no)
		(in_bom yes)
		(on_board yes)
		(dnp no)
		(fields_autoplaced yes)
		(property "Reference" "#PWR0112"
			(at 260.35 146.05 0)
			(effects
				(font
					(size 1.27 1.27)
				)
				(hide yes)
			)
		)
		(property "Value" "GND"
			(at 260.35 144.78 0)
			(effects
				(font
					(size 1.27 1.27)
				)
			)
		)
		(property "Footprint" ""
			(at 260.35 139.7 0)
			(effects
				(font
					(size 1.27 1.27)
				)
				(hide yes)
			)
		)
		(property "Datasheet" ""
			(at 260.35 139.7 0)
			(effects
				(font
					(size 1.27 1.27)
				)
				(hide yes)
			)
		)
		(property "Description" ""
			(at 260.35 139.7 0)
			(effects
				(font
					(size 1.27 1.27)
				)
			)
		)
		(pin "1"
		)
		(instances
			(project "ddr5-testbed"
				(path ""
					(reference "#PWR0112")
					(unit 1)
				)
			)
		)
	)
	(symbol
		(lib_id "antmicropower:GND")
		(at 194.31 139.7 0)
		(unit 1)
		(exclude_from_sim no)
		(in_bom yes)
		(on_board yes)
		(dnp no)
		(fields_autoplaced yes)
		(property "Reference" "#PWR0113"
			(at 194.31 146.05 0)
			(effects
				(font
					(size 1.27 1.27)
				)
				(hide yes)
			)
		)
		(property "Value" "GND"
			(at 194.31 144.78 0)
			(effects
				(font
					(size 1.27 1.27)
				)
			)
		)
		(property "Footprint" ""
			(at 194.31 139.7 0)
			(effects
				(font
					(size 1.27 1.27)
				)
				(hide yes)
			)
		)
		(property "Datasheet" ""
			(at 194.31 139.7 0)
			(effects
				(font
					(size 1.27 1.27)
				)
				(hide yes)
			)
		)
		(property "Description" ""
			(at 194.31 139.7 0)
			(effects
				(font
					(size 1.27 1.27)
				)
			)
		)
		(pin "1"
		)
		(instances
			(project "ddr5-testbed"
				(path ""
					(reference "#PWR0113")
					(unit 1)
				)
			)
		)
	)
	(symbol
		(lib_id "antmicroFixedInductors:L_2u2_1.5A_0806")
		(at 194.31 80.01 0)
		(unit 1)
		(exclude_from_sim no)
		(in_bom yes)
		(on_board yes)
		(dnp no)
		(property "Reference" "L1"
			(at 196.85 74.93 0)
			(effects
				(font
					(size 1.27 1.27)
				)
			)
		)
		(property "Value" "L_2.2u_1.5A_0806"
			(at 208.28 82.55 0)
			(effects
				(font
					(size 1.27 1.27)
					(thickness 0.15)
				)
				(justify left bottom)
				(hide yes)
			)
		)
		(property "Footprint" "antmicro-footprints:L_0806_2016Metric"
			(at 208.28 87.63 0)
			(effects
				(font
					(size 1.27 1.27)
					(thickness 0.15)
				)
				(justify left bottom)
				(hide yes)
			)
		)
		(property "Datasheet" "https://search.murata.co.jp/Ceramy/image/img/P02/J(E)TE243A-0011.pdf"
			(at 208.28 90.17 0)
			(effects
				(font
					(size 1.27 1.27)
					(thickness 0.15)
				)
				(justify left bottom)
				(hide yes)
			)
		)
		(property "Description" ""
			(at 194.31 80.01 0)
			(effects
				(font
					(size 1.27 1.27)
				)
			)
		)
		(property "Manufacturer" "Murata"
			(at 208.28 92.71 0)
			(effects
				(font
					(size 1.27 1.27)
					(thickness 0.15)
				)
				(justify left bottom)
				(hide yes)
			)
		)
		(property "MPN" "1285AS-H-2R2M=P2"
			(at 208.28 95.25 0)
			(effects
				(font
					(size 1.27 1.27)
					(thickness 0.15)
				)
				(justify left bottom)
				(hide yes)
			)
		)
		(property "Val" "2.2uH/1.5A"
			(at 196.85 77.47 0)
			(effects
				(font
					(size 1.27 1.27)
					(thickness 0.15)
				)
			)
		)
		(property "ISat" ""
			(at 208.28 96.52 0)
			(effects
				(font
					(size 1.27 1.27)
				)
				(justify left)
				(hide yes)
			)
		)
		(property "IMax" ""
			(at 208.28 100.33 0)
			(effects
				(font
					(size 1.27 1.27)
					(thickness 0.15)
				)
				(justify left bottom)
				(hide yes)
			)
		)
		(property "Size" "2.0x1.6"
			(at 208.28 102.87 0)
			(effects
				(font
					(size 1.27 1.27)
					(thickness 0.15)
				)
				(justify left bottom)
				(hide yes)
			)
		)
		(property "Author" "Antmicro"
			(at 208.28 105.41 0)
			(effects
				(font
					(size 1.27 1.27)
					(thickness 0.15)
				)
				(justify left bottom)
				(hide yes)
			)
		)
		(property "License" "Apache-2.0"
			(at 208.28 107.95 0)
			(effects
				(font
					(size 1.27 1.27)
					(thickness 0.15)
				)
				(justify left bottom)
				(hide yes)
			)
		)
		(pin "1"
		)
		(pin "2"
		)
		(instances
			(project "ddr5-testbed"
				(path ""
					(reference "L1")
					(unit 1)
				)
			)
		)
	)
	(symbol
		(lib_id "antmicroDCDCConverters:TPS613221A_SOT-23-5")
		(at 203.2 80.01 0)
		(unit 1)
		(exclude_from_sim no)
		(in_bom yes)
		(on_board yes)
		(dnp no)
		(property "Reference" "U2"
			(at 210.82 73.025 0)
			(effects
				(font
					(size 1.27 1.27)
				)
			)
		)
		(property "Value" "TPS613221A_SOT-23-5"
			(at 210.82 74.93 0)
			(effects
				(font
					(size 1.27 1.27)
					(thickness 0.15)
				)
				(hide yes)
			)
		)
		(property "Footprint" "antmicro-footprints:SOT-23-5"
			(at 236.22 87.63 0)
			(effects
				(font
					(size 1.27 1.27)
					(thickness 0.15)
				)
				(justify left bottom)
				(hide yes)
			)
		)
		(property "Datasheet" "https://www.ti.com/lit/ds/symlink/tps61322.pdf?ts=1679307661323&ref_url=https%253A%252F%252Fwww.ti.com%252Fproduct%252FTPS61322%252Fpart-details%252FTPS613221ADBVT%253Futm_source%253Dgoogle%2526utm_medium%253Dcpc%2526utm_campaign%253Docb-tistore-promo-app_opn_en-cpc-storeic-google-wwe%2526utm_content%253DDevice%2526ds_k%253DTPS613221ADBVT%2526DCM%253Dyes%2526gclid%253DCjwKCAjwiOCgBhAgEiwAjv5whAbq73RvnAdgvLpW8LFuSFEla1kNqoJei2y0mTqS4-Xlc-1KWPDvLxoCIUoQAvD_BwE%2526gclsrc%253Daw.ds"
			(at 236.22 90.17 0)
			(effects
				(font
					(size 1.27 1.27)
					(thickness 0.15)
				)
				(justify left bottom)
				(hide yes)
			)
		)
		(property "Description" ""
			(at 203.2 80.01 0)
			(effects
				(font
					(size 1.27 1.27)
				)
			)
		)
		(property "Manufacturer" "Texas Instruments"
			(at 236.22 92.71 0)
			(effects
				(font
					(size 1.27 1.27)
					(thickness 0.15)
				)
				(justify left bottom)
				(hide yes)
			)
		)
		(property "MPN" "TPS613221ADBVT"
			(at 210.82 75.565 0)
			(effects
				(font
					(size 1.27 1.27)
					(thickness 0.15)
				)
			)
		)
		(property "Author" "Antmicro"
			(at 236.22 97.79 0)
			(effects
				(font
					(size 1.27 1.27)
					(thickness 0.15)
				)
				(justify left bottom)
				(hide yes)
			)
		)
		(property "License" "Apache-2.0"
			(at 236.22 100.33 0)
			(effects
				(font
					(size 1.27 1.27)
					(thickness 0.15)
				)
				(justify left bottom)
				(hide yes)
			)
		)
		(pin "1"
		)
		(pin "2"
		)
		(pin "3"
		)
		(pin "4"
		)
		(pin "5"
		)
		(instances
			(project "ddr5-testbed"
				(path ""
					(reference "U2")
					(unit 1)
				)
			)
		)
	)
	(symbol
		(lib_id "antmicroResistors0402:R_10k_0402")
		(at 191.77 165.735 270)
		(unit 1)
		(exclude_from_sim no)
		(in_bom yes)
		(on_board yes)
		(dnp no)
		(fields_autoplaced yes)
		(property "Reference" "R14"
			(at 194.31 167.005 90)
			(effects
				(font
					(size 1.27 1.27)
				)
				(justify left)
			)
		)
		(property "Value" "R_10k_0402"
			(at 179.07 186.055 0)
			(effects
				(font
					(size 1.27 1.27)
					(thickness 0.15)
				)
				(justify left bottom)
				(hide yes)
			)
		)
		(property "Footprint" "antmicro-footprints:R_0402_1005Metric"
			(at 176.53 186.055 0)
			(effects
				(font
					(size 1.27 1.27)
					(thickness 0.15)
				)
				(justify left bottom)
				(hide yes)
			)
		)
		(property "Datasheet" "https://www.bourns.com/docs/product-datasheets/cr.pdf"
			(at 173.99 186.055 0)
			(effects
				(font
					(size 1.27 1.27)
					(thickness 0.15)
				)
				(justify left bottom)
				(hide yes)
			)
		)
		(property "Description" ""
			(at 191.77 165.735 0)
			(effects
				(font
					(size 1.27 1.27)
				)
			)
		)
		(property "Manufacturer" "Bourns"
			(at 168.91 186.055 0)
			(effects
				(font
					(size 1.27 1.27)
					(thickness 0.15)
				)
				(justify left bottom)
				(hide yes)
			)
		)
		(property "MPN" "CR0402-FX-1002GLF"
			(at 171.45 186.055 0)
			(effects
				(font
					(size 1.27 1.27)
					(thickness 0.15)
				)
				(justify left bottom)
				(hide yes)
			)
		)
		(property "Val" "10k"
			(at 194.31 170.1799 90)
			(effects
				(font
					(size 1.27 1.27)
					(thickness 0.15)
				)
				(justify left)
			)
		)
		(property "License" "Apache-2.0"
			(at 166.37 186.055 0)
			(effects
				(font
					(size 1.27 1.27)
					(thickness 0.15)
				)
				(justify left bottom)
				(hide yes)
			)
		)
		(property "Author" "Antmicro"
			(at 163.83 186.055 0)
			(effects
				(font
					(size 1.27 1.27)
					(thickness 0.15)
				)
				(justify left bottom)
				(hide yes)
			)
		)
		(property "Tolerance" "1%"
			(at 181.61 186.055 0)
			(effects
				(font
					(size 1.27 1.27)
				)
				(justify left bottom)
				(hide yes)
			)
		)
		(pin "1"
		)
		(pin "2"
		)
		(instances
			(project "ddr5-testbed"
				(path ""
					(reference "R14")
					(unit 1)
				)
			)
		)
	)
	(symbol
		(lib_id "antmicropower:GND")
		(at 196.85 180.34 0)
		(unit 1)
		(exclude_from_sim no)
		(in_bom yes)
		(on_board yes)
		(dnp no)
		(fields_autoplaced yes)
		(property "Reference" "#PWR0114"
			(at 196.85 186.69 0)
			(effects
				(font
					(size 1.27 1.27)
				)
				(hide yes)
			)
		)
		(property "Value" "GND"
			(at 196.85 185.42 0)
			(effects
				(font
					(size 1.27 1.27)
				)
			)
		)
		(property "Footprint" ""
			(at 196.85 180.34 0)
			(effects
				(font
					(size 1.27 1.27)
				)
				(hide yes)
			)
		)
		(property "Datasheet" ""
			(at 196.85 180.34 0)
			(effects
				(font
					(size 1.27 1.27)
				)
				(hide yes)
			)
		)
		(property "Description" ""
			(at 196.85 180.34 0)
			(effects
				(font
					(size 1.27 1.27)
				)
			)
		)
		(pin "1"
		)
		(instances
			(project "ddr5-testbed"
				(path ""
					(reference "#PWR0114")
					(unit 1)
				)
			)
		)
	)
	(symbol
		(lib_id "antmicroTestPoints:TP_1mm_SMD")
		(at 194.945 179.07 180)
		(unit 1)
		(exclude_from_sim no)
		(in_bom yes)
		(on_board yes)
		(dnp no)
		(fields_autoplaced yes)
		(property "Reference" "TP3"
			(at 189.23 179.0699 0)
			(effects
				(font
					(size 1.27 1.27)
				)
				(justify left)
			)
		)
		(property "Value" "TP_1mm_SMD"
			(at 179.705 171.45 0)
			(effects
				(font
					(size 1.27 1.27)
					(thickness 0.15)
				)
				(justify left bottom)
				(hide yes)
			)
		)
		(property "Footprint" "antmicro-footprints:TP_SMD_1mm"
			(at 179.705 168.91 0)
			(effects
				(font
					(size 1.27 1.27)
					(thickness 0.15)
				)
				(justify left bottom)
				(hide yes)
			)
		)
		(property "Datasheet" ""
			(at 179.705 166.37 0)
			(effects
				(font
					(size 1.27 1.27)
					(thickness 0.15)
				)
				(justify left bottom)
				(hide yes)
			)
		)
		(property "Description" ""
			(at 194.945 179.07 0)
			(effects
				(font
					(size 1.27 1.27)
				)
			)
		)
		(property "MPN" ""
			(at 194.945 179.07 0)
			(effects
				(font
					(size 1.27 1.27)
				)
				(hide yes)
			)
		)
		(property "Manufacturer" ""
			(at 194.945 179.07 0)
			(effects
				(font
					(size 1.27 1.27)
				)
				(hide yes)
			)
		)
		(property "Author" "Antmicro"
			(at 179.705 163.83 0)
			(effects
				(font
					(size 1.27 1.27)
					(thickness 0.15)
				)
				(justify left bottom)
				(hide yes)
			)
		)
		(property "License" "Apache-2.0"
			(at 179.705 161.29 0)
			(effects
				(font
					(size 1.27 1.27)
					(thickness 0.15)
				)
				(justify left bottom)
				(hide yes)
			)
		)
		(pin "1"
		)
		(instances
			(project "ddr5-testbed"
				(path ""
					(reference "TP3")
					(unit 1)
				)
			)
		)
	)
	(symbol
		(lib_id "antmicropower:GND")
		(at 219.71 180.34 0)
		(unit 1)
		(exclude_from_sim no)
		(in_bom yes)
		(on_board yes)
		(dnp no)
		(fields_autoplaced yes)
		(property "Reference" "#PWR0115"
			(at 219.71 186.69 0)
			(effects
				(font
					(size 1.27 1.27)
				)
				(hide yes)
			)
		)
		(property "Value" "GND"
			(at 219.71 185.42 0)
			(effects
				(font
					(size 1.27 1.27)
				)
			)
		)
		(property "Footprint" ""
			(at 219.71 180.34 0)
			(effects
				(font
					(size 1.27 1.27)
				)
				(hide yes)
			)
		)
		(property "Datasheet" ""
			(at 219.71 180.34 0)
			(effects
				(font
					(size 1.27 1.27)
				)
				(hide yes)
			)
		)
		(property "Description" ""
			(at 219.71 180.34 0)
			(effects
				(font
					(size 1.27 1.27)
				)
			)
		)
		(pin "1"
		)
		(instances
			(project "ddr5-testbed"
				(path ""
					(reference "#PWR0115")
					(unit 1)
				)
			)
		)
	)
	(symbol
		(lib_id "antmicropower:GND")
		(at 252.095 180.34 0)
		(unit 1)
		(exclude_from_sim no)
		(in_bom yes)
		(on_board yes)
		(dnp no)
		(fields_autoplaced yes)
		(property "Reference" "#PWR0116"
			(at 252.095 186.69 0)
			(effects
				(font
					(size 1.27 1.27)
				)
				(hide yes)
			)
		)
		(property "Value" "GND"
			(at 252.095 184.785 0)
			(effects
				(font
					(size 1.27 1.27)
				)
			)
		)
		(property "Footprint" ""
			(at 252.095 180.34 0)
			(effects
				(font
					(size 1.27 1.27)
				)
				(hide yes)
			)
		)
		(property "Datasheet" ""
			(at 252.095 180.34 0)
			(effects
				(font
					(size 1.27 1.27)
				)
				(hide yes)
			)
		)
		(property "Description" ""
			(at 252.095 180.34 0)
			(effects
				(font
					(size 1.27 1.27)
				)
			)
		)
		(pin "1"
		)
		(instances
			(project "ddr5-testbed"
				(path ""
					(reference "#PWR0116")
					(unit 1)
				)
			)
		)
	)
	(symbol
		(lib_id "antmicroCapacitors0402:C_100n_0402")
		(at 259.715 175.26 270)
		(unit 1)
		(exclude_from_sim no)
		(in_bom yes)
		(on_board yes)
		(dnp no)
		(property "Reference" "C39"
			(at 260.35 175.895 90)
			(effects
				(font
					(size 1.27 1.27)
				)
				(justify left)
			)
		)
		(property "Value" "C_100n_0402"
			(at 249.555 195.58 0)
			(effects
				(font
					(size 1.27 1.27)
					(thickness 0.15)
				)
				(justify left bottom)
				(hide yes)
			)
		)
		(property "Footprint" "antmicro-footprints:C_0402_1005Metric"
			(at 247.015 195.58 0)
			(effects
				(font
					(size 1.27 1.27)
					(thickness 0.15)
				)
				(justify left bottom)
				(hide yes)
			)
		)
		(property "Datasheet" "https://search.murata.co.jp/Ceramy/image/img/A01X/G101/ENG/GRM155R61H104KE14-01.pdf"
			(at 244.475 195.58 0)
			(effects
				(font
					(size 1.27 1.27)
					(thickness 0.15)
				)
				(justify left bottom)
				(hide yes)
			)
		)
		(property "Description" ""
			(at 259.715 175.26 0)
			(effects
				(font
					(size 1.27 1.27)
				)
			)
		)
		(property "Manufacturer" "Murata"
			(at 239.395 195.58 0)
			(effects
				(font
					(size 1.27 1.27)
					(thickness 0.15)
				)
				(justify left bottom)
				(hide yes)
			)
		)
		(property "MPN" "GRM155R61H104KE14D"
			(at 241.935 195.58 0)
			(effects
				(font
					(size 1.27 1.27)
					(thickness 0.15)
				)
				(justify left bottom)
				(hide yes)
			)
		)
		(property "Val" "100n"
			(at 260.35 179.705 90)
			(effects
				(font
					(size 1.27 1.27)
					(thickness 0.15)
				)
				(justify left)
			)
		)
		(property "License" "Apache-2.0"
			(at 236.855 195.58 0)
			(effects
				(font
					(size 1.27 1.27)
					(thickness 0.15)
				)
				(justify left bottom)
				(hide yes)
			)
		)
		(property "Author" "Antmicro"
			(at 234.315 195.58 0)
			(effects
				(font
					(size 1.27 1.27)
					(thickness 0.15)
				)
				(justify left bottom)
				(hide yes)
			)
		)
		(property "Voltage" "50V"
			(at 231.775 195.58 0)
			(effects
				(font
					(size 1.27 1.27)
				)
				(justify left bottom)
				(hide yes)
			)
		)
		(property "Dielectric" "X5R"
			(at 229.235 195.58 0)
			(effects
				(font
					(size 1.27 1.27)
				)
				(justify left bottom)
				(hide yes)
			)
		)
		(pin "1"
		)
		(pin "2"
		)
		(instances
			(project "ddr5-testbed"
				(path ""
					(reference "C39")
					(unit 1)
				)
			)
		)
	)
	(symbol
		(lib_id "antmicropower:GND")
		(at 259.715 180.34 0)
		(unit 1)
		(exclude_from_sim no)
		(in_bom yes)
		(on_board yes)
		(dnp no)
		(fields_autoplaced yes)
		(property "Reference" "#PWR0117"
			(at 259.715 186.69 0)
			(effects
				(font
					(size 1.27 1.27)
				)
				(hide yes)
			)
		)
		(property "Value" "GND"
			(at 259.715 184.785 0)
			(effects
				(font
					(size 1.27 1.27)
				)
			)
		)
		(property "Footprint" ""
			(at 259.715 180.34 0)
			(effects
				(font
					(size 1.27 1.27)
				)
				(hide yes)
			)
		)
		(property "Datasheet" ""
			(at 259.715 180.34 0)
			(effects
				(font
					(size 1.27 1.27)
				)
				(hide yes)
			)
		)
		(property "Description" ""
			(at 259.715 180.34 0)
			(effects
				(font
					(size 1.27 1.27)
				)
			)
		)
		(pin "1"
		)
		(instances
			(project "ddr5-testbed"
				(path ""
					(reference "#PWR0117")
					(unit 1)
				)
			)
		)
	)
	(symbol
		(lib_id "antmicroInterfaceIOExpanders:PCA6408A_TSSOP")
		(at 195.58 111.76 0)
		(unit 1)
		(exclude_from_sim no)
		(in_bom yes)
		(on_board yes)
		(dnp no)
		(property "Reference" "IC1"
			(at 206.375 105.41 0)
			(effects
				(font
					(size 1.27 1.27)
				)
			)
		)
		(property "Value" "PCA6408A_TSSOP"
			(at 206.375 106.045 0)
			(effects
				(font
					(size 1.27 1.27)
					(thickness 0.15)
				)
				(hide yes)
			)
		)
		(property "Footprint" "antmicro-footprints:TSSOP-16_4.4x5mm_P0.65mm"
			(at 231.14 119.38 0)
			(effects
				(font
					(size 1.27 1.27)
					(thickness 0.15)
				)
				(justify left bottom)
				(hide yes)
			)
		)
		(property "Datasheet" "https://www.mouser.com/datasheet/2/302/PCA6408A-1127604.pdf"
			(at 231.14 121.92 0)
			(effects
				(font
					(size 1.27 1.27)
					(thickness 0.15)
				)
				(justify left bottom)
				(hide yes)
			)
		)
		(property "Description" ""
			(at 195.58 111.76 0)
			(effects
				(font
					(size 1.27 1.27)
				)
			)
		)
		(property "Manufacturer" "NXP"
			(at 231.14 124.46 0)
			(effects
				(font
					(size 1.27 1.27)
					(thickness 0.15)
				)
				(justify left bottom)
				(hide yes)
			)
		)
		(property "MPN" "PCA6408APW"
			(at 200.025 108.585 0)
			(effects
				(font
					(size 1.27 1.27)
					(thickness 0.15)
				)
				(justify left bottom)
			)
		)
		(property "Author" "Antmicro"
			(at 231.14 129.54 0)
			(effects
				(font
					(size 1.27 1.27)
					(thickness 0.15)
				)
				(justify left bottom)
				(hide yes)
			)
		)
		(property "License" "Apache-2.0"
			(at 231.14 132.08 0)
			(effects
				(font
					(size 1.27 1.27)
					(thickness 0.15)
				)
				(justify left bottom)
				(hide yes)
			)
		)
		(pin "1"
		)
		(pin "10"
		)
		(pin "11"
		)
		(pin "12"
		)
		(pin "13"
		)
		(pin "14"
		)
		(pin "15"
		)
		(pin "16"
		)
		(pin "2"
		)
		(pin "3"
		)
		(pin "4"
		)
		(pin "5"
		)
		(pin "6"
		)
		(pin "7"
		)
		(pin "8"
		)
		(pin "9"
		)
		(instances
			(project "ddr5-testbed"
				(path ""
					(reference "IC1")
					(unit 1)
				)
			)
		)
	)
	(symbol
		(lib_id "antmicroTestPoints:TP_1mm_SMD")
		(at 219.71 124.46 0)
		(unit 1)
		(exclude_from_sim no)
		(in_bom yes)
		(on_board yes)
		(dnp no)
		(fields_autoplaced yes)
		(property "Reference" "TP2"
			(at 224.79 124.4599 0)
			(effects
				(font
					(size 1.27 1.27)
				)
				(justify left)
			)
		)
		(property "Value" "TP_1mm_SMD"
			(at 234.95 132.08 0)
			(effects
				(font
					(size 1.27 1.27)
					(thickness 0.15)
				)
				(justify left bottom)
				(hide yes)
			)
		)
		(property "Footprint" "antmicro-footprints:TP_SMD_1mm"
			(at 234.95 134.62 0)
			(effects
				(font
					(size 1.27 1.27)
					(thickness 0.15)
				)
				(justify left bottom)
				(hide yes)
			)
		)
		(property "Datasheet" ""
			(at 234.95 137.16 0)
			(effects
				(font
					(size 1.27 1.27)
					(thickness 0.15)
				)
				(justify left bottom)
				(hide yes)
			)
		)
		(property "Description" ""
			(at 219.71 124.46 0)
			(effects
				(font
					(size 1.27 1.27)
				)
			)
		)
		(property "MPN" ""
			(at 219.71 124.46 0)
			(effects
				(font
					(size 1.27 1.27)
				)
				(hide yes)
			)
		)
		(property "Manufacturer" ""
			(at 219.71 124.46 0)
			(effects
				(font
					(size 1.27 1.27)
				)
				(hide yes)
			)
		)
		(property "Author" "Antmicro"
			(at 234.95 139.7 0)
			(effects
				(font
					(size 1.27 1.27)
					(thickness 0.15)
				)
				(justify left bottom)
				(hide yes)
			)
		)
		(property "License" "Apache-2.0"
			(at 234.95 142.24 0)
			(effects
				(font
					(size 1.27 1.27)
					(thickness 0.15)
				)
				(justify left bottom)
				(hide yes)
			)
		)
		(pin "1"
		)
		(instances
			(project "ddr5-testbed"
				(path ""
					(reference "TP2")
					(unit 1)
				)
			)
		)
	)
	(symbol
		(lib_id "antmicroTestPoints:TP_1mm_SMD")
		(at 219.71 121.92 0)
		(unit 1)
		(exclude_from_sim no)
		(in_bom yes)
		(on_board yes)
		(dnp no)
		(fields_autoplaced yes)
		(property "Reference" "TP1"
			(at 224.79 121.9199 0)
			(effects
				(font
					(size 1.27 1.27)
				)
				(justify left)
			)
		)
		(property "Value" "TP_1mm_SMD"
			(at 234.95 129.54 0)
			(effects
				(font
					(size 1.27 1.27)
					(thickness 0.15)
				)
				(justify left bottom)
				(hide yes)
			)
		)
		(property "Footprint" "antmicro-footprints:TP_SMD_1mm"
			(at 234.95 132.08 0)
			(effects
				(font
					(size 1.27 1.27)
					(thickness 0.15)
				)
				(justify left bottom)
				(hide yes)
			)
		)
		(property "Datasheet" ""
			(at 234.95 134.62 0)
			(effects
				(font
					(size 1.27 1.27)
					(thickness 0.15)
				)
				(justify left bottom)
				(hide yes)
			)
		)
		(property "Description" ""
			(at 219.71 121.92 0)
			(effects
				(font
					(size 1.27 1.27)
				)
			)
		)
		(property "MPN" ""
			(at 219.71 121.92 0)
			(effects
				(font
					(size 1.27 1.27)
				)
				(hide yes)
			)
		)
		(property "Manufacturer" ""
			(at 219.71 121.92 0)
			(effects
				(font
					(size 1.27 1.27)
				)
				(hide yes)
			)
		)
		(property "Author" "Antmicro"
			(at 234.95 137.16 0)
			(effects
				(font
					(size 1.27 1.27)
					(thickness 0.15)
				)
				(justify left bottom)
				(hide yes)
			)
		)
		(property "License" "Apache-2.0"
			(at 234.95 139.7 0)
			(effects
				(font
					(size 1.27 1.27)
					(thickness 0.15)
				)
				(justify left bottom)
				(hide yes)
			)
		)
		(pin "1"
		)
		(instances
			(project "ddr5-testbed"
				(path ""
					(reference "TP1")
					(unit 1)
				)
			)
		)
	)
)
